G04*
G04 #@! TF.GenerationSoftware,Altium Limited,Altium Designer,23.0.1 (38)*
G04*
G04 Layer_Color=128*
%FSLAX44Y44*%
%MOMM*%
G71*
G04*
G04 #@! TF.SameCoordinates,9A23C038-B079-480F-8166-AFFB5740F5AE*
G04*
G04*
G04 #@! TF.FilePolarity,Positive*
G04*
G01*
G75*
M02*
